# S9S_MB_2U (Grand Teton) — schematic netlist excerpt (pin names and nets, part order shuffled) for the footprints in the layout excerpt that follows; sources: Cadence DE-HDL packaged netlist, KiCad conversion of 03242023_DA0F0TMBIJ0_F0T_Motherboard_J_brd_V01_OCP.brd

C433  Q_CAP  22UF 4V 20% X6S  pkg C0402  page 77 : A = PVCCFA_EHV_FIVRA_CPU1 ; B = GND
C836  Q_CAP_DIFFBUS  DIFF BUS_0.22UF 6.3V 20% X6S  pkg C0201  page 175 : \1\ = P5E_CPU1_PE1_TX_C_DN<0> ; \2\ = P5E_CPU1_PE1_TX_DN<0>
PC2237  Q_CAP  3900PF 50V 10% EMPTY  pkg C0402  page 242 : A = P12V_SCM_GATE ; B = GND

(kicad_pcb
	(version 20260206)
	(generator "pcbnew")
	(generator_version "10.0")
	(general
		(thickness 1.6)
		(legacy_teardrops no)
	)
	(paper "A4")
	(title_block
		(title "03242023_DA0F0TMBIJ0_F0T_Motherboard_J_brd_V01_OCP.brd")
		(comment 1 "Grand Teton / footprints 438-440 of 6105")
	)
	(layers
		(0 "F.Cu" signal "TOP")
		(4 "In1.Cu" signal "GND")
		(6 "In2.Cu" signal "IN1")
		(8 "In3.Cu" signal "GND1")
		(10 "In4.Cu" signal "IN2")
		(12 "In5.Cu" signal "GND2")
		(14 "In6.Cu" signal "IN3")
		(16 "In7.Cu" signal "GND3")
		(18 "In8.Cu" signal "VCC")
		(20 "In9.Cu" signal "VCC1")
		(22 "In10.Cu" signal "GND4")
		(24 "In11.Cu" signal "IN4")
		(26 "In12.Cu" signal "GND5")
		(28 "In13.Cu" signal "IN5")
		(30 "In14.Cu" signal "GND6")
		(32 "In15.Cu" signal "IN6")
		(34 "In16.Cu" signal "GND7")
		(2 "B.Cu" signal "BOTTOM")
		(9 "F.Adhes" user "F.Adhesive")
		(11 "B.Adhes" user "B.Adhesive")
		(13 "F.Paste" user "Package Geometry/Pastemask Top")
		(15 "B.Paste" user "Package Geometry/Pastemask Bottom")
		(5 "F.SilkS" user "Ref Des/Silkscreen Top")
		(7 "B.SilkS" user "Ref Des/Silkscreen Bottom")
		(1 "F.Mask" user "Board Geometry/Soldermask Top")
		(3 "B.Mask" user "Board Geometry/Soldermask Bottom")
		(17 "Dwgs.User" user "User.Drawings")
		(19 "Cmts.User" user "User.Comments")
		(21 "Eco1.User" user "User.Eco1")
		(23 "Eco2.User" user "User.Eco2")
		(25 "Edge.Cuts" user "Board Geometry/Outline")
		(27 "Margin" user)
		(31 "F.CrtYd" user "Package Geometry/Place Bound Top")
		(29 "B.CrtYd" user "Package Geometry/Place Bound Bottom")
		(35 "F.Fab" user "Ref Des/Assembly Top")
		(33 "B.Fab" user "Ref Des/Assembly Bottom")
	)
	(footprint ""
		(layer "F.Cu")
		(at 107.287314 -260.36524 -90)
		(property "Reference" "C433"
			(at 0 0 270)
			(layer "F.SilkS")
			(hide yes)
			(effects
				(font
					(size 1.27 1.27)
				)
			)
		)
		(property "Value" ""
			(at 0 0 270)
			(layer "F.Fab")
			(effects
				(font
					(size 1.27 1.27)
				)
			)
		)
		(duplicate_pad_numbers_are_jumpers no)
		(fp_line
			(start -0.7874 0.4064)
			(end -0.7874 -0.4064)
			(stroke
				(width 0.1524)
				(type default)
			)
			(layer "F.SilkS")
		)
		(fp_line
			(start 0.7874 0.4064)
			(end -0.7874 0.4064)
			(stroke
				(width 0.1524)
				(type default)
			)
			(layer "F.SilkS")
		)
		(fp_line
			(start -0.7874 -0.4064)
			(end 0.7874 -0.4064)
			(stroke
				(width 0.1524)
				(type default)
			)
			(layer "F.SilkS")
		)
		(fp_line
			(start 0.7874 -0.4064)
			(end 0.7874 0.4064)
			(stroke
				(width 0.1524)
				(type default)
			)
			(layer "F.SilkS")
		)
		(fp_line
			(start -0.67945 0.3048)
			(end -0.67945 -0.305054)
			(stroke
				(width 0.1)
				(type default)
			)
			(layer "F.Fab")
		)
		(fp_line
			(start -0.12065 0.3048)
			(end -0.67945 0.3048)
			(stroke
				(width 0.1)
				(type default)
			)
			(layer "F.Fab")
		)
		(fp_line
			(start 0.120396 0.3048)
			(end 0.120396 0.2794)
			(stroke
				(width 0.1)
				(type default)
			)
			(layer "F.Fab")
		)
		(fp_line
			(start 0.67945 0.3048)
			(end 0.120396 0.3048)
			(stroke
				(width 0.1)
				(type default)
			)
			(layer "F.Fab")
		)
		(fp_line
			(start -0.12065 0.2794)
			(end -0.12065 0.3048)
			(stroke
				(width 0.1)
				(type default)
			)
			(layer "F.Fab")
		)
		(fp_line
			(start 0.120396 0.2794)
			(end -0.12065 0.2794)
			(stroke
				(width 0.1)
				(type default)
			)
			(layer "F.Fab")
		)
		(fp_line
			(start -0.12065 -0.2794)
			(end 0.12065 -0.2794)
			(stroke
				(width 0.1)
				(type default)
			)
			(layer "F.Fab")
		)
		(fp_line
			(start 0.12065 -0.2794)
			(end 0.12065 -0.3048)
			(stroke
				(width 0.1)
				(type default)
			)
			(layer "F.Fab")
		)
		(fp_line
			(start 0.12065 -0.3048)
			(end 0.67945 -0.3048)
			(stroke
				(width 0.1)
				(type default)
			)
			(layer "F.Fab")
		)
		(fp_line
			(start 0.67945 -0.3048)
			(end 0.67945 0.3048)
			(stroke
				(width 0.1)
				(type default)
			)
			(layer "F.Fab")
		)
		(fp_line
			(start -0.67945 -0.305054)
			(end -0.12065 -0.305054)
			(stroke
				(width 0.1)
				(type default)
			)
			(layer "F.Fab")
		)
		(fp_line
			(start -0.12065 -0.305054)
			(end -0.12065 -0.2794)
			(stroke
				(width 0.1)
				(type default)
			)
			(layer "F.Fab")
		)
		(pad "1" smd circle
			(at -0.40005 0 270)
			(size 0 0)
			(layers "F.Cu" "F.Mask" "F.Paste")
			(net "PVCCFA_EHV_FIVRA_CPU1")
		)
		(pad "2" smd circle
			(at 0.40005 0 270)
			(size 0 0)
			(layers "F.Cu" "F.Mask" "F.Paste")
			(net "GND")
		)
	)
	(footprint ""
		(layer "F.Cu")
		(at 191.295782 -28.267152)
		(property "Reference" "PC2237"
			(at 0 0 0)
			(layer "F.SilkS")
			(hide yes)
			(effects
				(font
					(size 1.27 1.27)
				)
			)
		)
		(property "Value" ""
			(at 0 0 0)
			(layer "F.Fab")
			(effects
				(font
					(size 1.27 1.27)
				)
			)
		)
		(duplicate_pad_numbers_are_jumpers no)
		(fp_line
			(start -0.7874 -0.4064)
			(end 0.7874 -0.4064)
			(stroke
				(width 0.1524)
				(type default)
			)
			(layer "F.SilkS")
		)
		(fp_line
			(start -0.7874 0.4064)
			(end -0.7874 -0.4064)
			(stroke
				(width 0.1524)
				(type default)
			)
			(layer "F.SilkS")
		)
		(fp_line
			(start 0.7874 -0.4064)
			(end 0.7874 0.4064)
			(stroke
				(width 0.1524)
				(type default)
			)
			(layer "F.SilkS")
		)
		(fp_line
			(start 0.7874 0.4064)
			(end -0.7874 0.4064)
			(stroke
				(width 0.1524)
				(type default)
			)
			(layer "F.SilkS")
		)
		(fp_line
			(start -0.67945 -0.305054)
			(end -0.12065 -0.305054)
			(stroke
				(width 0.1)
				(type default)
			)
			(layer "F.Fab")
		)
		(fp_line
			(start -0.67945 0.3048)
			(end -0.67945 -0.305054)
			(stroke
				(width 0.1)
				(type default)
			)
			(layer "F.Fab")
		)
		(fp_line
			(start -0.12065 -0.305054)
			(end -0.12065 -0.2794)
			(stroke
				(width 0.1)
				(type default)
			)
			(layer "F.Fab")
		)
		(fp_line
			(start -0.12065 -0.2794)
			(end 0.12065 -0.2794)
			(stroke
				(width 0.1)
				(type default)
			)
			(layer "F.Fab")
		)
		(fp_line
			(start -0.12065 0.2794)
			(end -0.12065 0.3048)
			(stroke
				(width 0.1)
				(type default)
			)
			(layer "F.Fab")
		)
		(fp_line
			(start -0.12065 0.3048)
			(end -0.67945 0.3048)
			(stroke
				(width 0.1)
				(type default)
			)
			(layer "F.Fab")
		)
		(fp_line
			(start 0.120396 0.2794)
			(end -0.12065 0.2794)
			(stroke
				(width 0.1)
				(type default)
			)
			(layer "F.Fab")
		)
		(fp_line
			(start 0.120396 0.3048)
			(end 0.120396 0.2794)
			(stroke
				(width 0.1)
				(type default)
			)
			(layer "F.Fab")
		)
		(fp_line
			(start 0.12065 -0.3048)
			(end 0.67945 -0.3048)
			(stroke
				(width 0.1)
				(type default)
			)
			(layer "F.Fab")
		)
		(fp_line
			(start 0.12065 -0.2794)
			(end 0.12065 -0.3048)
			(stroke
				(width 0.1)
				(type default)
			)
			(layer "F.Fab")
		)
		(fp_line
			(start 0.67945 -0.3048)
			(end 0.67945 0.3048)
			(stroke
				(width 0.1)
				(type default)
			)
			(layer "F.Fab")
		)
		(fp_line
			(start 0.67945 0.3048)
			(end 0.120396 0.3048)
			(stroke
				(width 0.1)
				(type default)
			)
			(layer "F.Fab")
		)
		(pad "1" smd circle
			(at -0.40005 0)
			(size 0 0)
			(layers "F.Cu" "F.Mask" "F.Paste")
			(net "P12V_SCM_GATE")
		)
		(pad "2" smd circle
			(at 0.40005 0)
			(size 0 0)
			(layers "F.Cu" "F.Mask" "F.Paste")
			(net "GND")
		)
	)
	(footprint ""
		(layer "F.Cu")
		(at 57.75833 -17.623536 90)
		(property "Reference" "C836"
			(at 0 0 90)
			(layer "F.SilkS")
			(hide yes)
			(effects
				(font
					(size 1.27 1.27)
				)
			)
		)
		(property "Value" ""
			(at 0 0 90)
			(layer "F.Fab")
			(effects
				(font
					(size 1.27 1.27)
				)
			)
		)
		(duplicate_pad_numbers_are_jumpers no)
		(fp_line
			(start 0.299974 -0.150114)
			(end 0.299974 0.150114)
			(stroke
				(width 0.1)
				(type default)
			)
			(layer "F.Fab")
		)
		(fp_line
			(start -0.299974 -0.150114)
			(end 0.299974 -0.150114)
			(stroke
				(width 0.1)
				(type default)
			)
			(layer "F.Fab")
		)
		(fp_line
			(start 0.299974 0.150114)
			(end -0.299974 0.150114)
			(stroke
				(width 0.1)
				(type default)
			)
			(layer "F.Fab")
		)
		(fp_line
			(start -0.299974 0.150114)
			(end -0.299974 -0.150114)
			(stroke
				(width 0.1)
				(type default)
			)
			(layer "F.Fab")
		)
		(pad "1" smd rect
			(at -0.2667 0 90)
			(size 0.3048 0.381)
			(layers "F.Cu" "F.Mask" "F.Paste")
			(net "P5E_CPU1_PE1_TX_C_DN<0>")
		)
		(pad "2" smd rect
			(at 0.2667 0 90)
			(size 0.3048 0.381)
			(layers "F.Cu" "F.Mask" "F.Paste")
			(net "P5E_CPU1_PE1_TX_DN<0>")
		)
	)
)
